#ISCELL
  mstr_symbols cad_note *
  *
#ISCELL
  mstr_symbols design_note *
  *
#ISCELL
  mstr_symbols intel_corp_bpage *
  *
#ISCELL
  mstr_standard offpage *
  page248_i10
#CELL
  mstr_ttl ttl1g08 *
  page248_i11
#ISCELL
  mstr_standard offpage *
  page248_i12
#CELL
  dev_discrete cap_a *
  page248_i13
#ISCELL
  mstr_symbols gnd *
  page248_i15
#ISCELL
  mstr_symbols p3v3 *
  page248_i16
#CELL
  dev_discrete cap_a *
  page248_i17
#ISCELL
  mstr_symbols gnd *
  page248_i18
#CELL
  mstr_ttl ttl1g08 *
  page248_i19
#ISCELL
  mstr_standard offpage *
  page248_i20
#ISCELL
  mstr_standard offpage *
  page248_i21
#ISCELL
  mstr_standard offpage *
  page248_i22
#ISCELL
  mstr_standard offpage *
  page248_i23
#CELL
  mstr_discrete res *
  page248_i24
#CELL
  mstr_discrete res *
  page248_i25
#CELL
  mstr_discrete res *
  page248_i26
#CELL
  mstr_discrete res *
  page248_i27
#ISCELL
  mstr_symbols gnd *
  page248_i29
#CELL
  dev_discrete cap_a *
  page248_i30
#ISCELL
  mstr_symbols gnd *
  page248_i31
#CELL
  dev_discrete cap_a *
  page248_i32
#CELL
  mstr_discrete res *
  page248_i34
#CELL
  mstr_discrete res *
  page248_i35
#ISCELL
  mstr_symbols p3v3_stby *
  page248_i36
#CELL
  mstr_discrete res *
  page248_i37
#CELL
  mstr_discrete res *
  page248_i38
#ISCELL
  mstr_symbols p3v3_stby *
  page248_i40
#ISCELL
  mstr_standard offpage *
  page248_i44
#ISCELL
  mstr_standard offpage *
  page248_i45
#ISCELL
  mstr_symbols pvccio_cpu0 *
  page248_i47
#ISCELL
  mstr_symbols pvccio_cpu0 *
  page248_i48
#CELL
  w_hdl tca9517dgkr-gp *
  page248_i49
#ISCELL
  mstr_symbols gnd *
  page248_i50
#ISCELL
  mstr_standard offpage *
  page248_i51
#ISCELL
  mstr_standard offpage *
  page248_i52
#ISCELL
  mstr_symbols p3v3 *
  page248_i9
